(kicad_pcb
	(version 20260206)
	(generator "pcbnew")
	(generator_version "10.0")
	(general
		(thickness 1.6)
		(legacy_teardrops no)
	)
	(paper "A4")
	(title_block
		(title "01162023_DA0F0TEBIF0_F0T_Expander_BD_F_brd_V02_OCP.brd")
		(comment 1 "Grand Teton / footprints 6443-6449 of 9728")
	)
	(layers
		(0 "F.Cu" signal "TOP")
		(4 "In1.Cu" signal "GND")
		(6 "In2.Cu" signal "VCC")
		(8 "In3.Cu" signal "VCC1")
		(10 "In4.Cu" signal "GND1")
		(12 "In5.Cu" signal "IN1")
		(14 "In6.Cu" signal "GND2")
		(16 "In7.Cu" signal "IN2")
		(18 "In8.Cu" signal "GND3")
		(20 "In9.Cu" signal "IN3")
		(22 "In10.Cu" signal "GND4")
		(24 "In11.Cu" signal "IN4")
		(26 "In12.Cu" signal "GND5")
		(28 "In13.Cu" signal "IN5")
		(30 "In14.Cu" signal "GND6")
		(32 "In15.Cu" signal "IN6")
		(34 "In16.Cu" signal "GND7")
		(2 "B.Cu" signal "BOTTOM")
		(9 "F.Adhes" user "F.Adhesive")
		(11 "B.Adhes" user "B.Adhesive")
		(13 "F.Paste" user "Package Geometry/Pastemask Top")
		(15 "B.Paste" user "Package Geometry/Pastemask Bottom")
		(5 "F.SilkS" user "Ref Des/Silkscreen Top")
		(7 "B.SilkS" user "Ref Des/Silkscreen Bottom")
		(1 "F.Mask" user "Board Geometry/Soldermask Top")
		(3 "B.Mask" user "Board Geometry/Soldermask Bottom")
		(17 "Dwgs.User" user "User.Drawings")
		(19 "Cmts.User" user "User.Comments")
		(21 "Eco1.User" user "User.Eco1")
		(23 "Eco2.User" user "User.Eco2")
		(25 "Edge.Cuts" user "Board Geometry/Outline")
		(27 "Margin" user)
		(31 "F.CrtYd" user "Package Geometry/Place Bound Top")
		(29 "B.CrtYd" user "Package Geometry/Place Bound Bottom")
		(35 "F.Fab" user "Ref Des/Assembly Top")
		(33 "B.Fab" user "Ref Des/Assembly Bottom")
	)
	(footprint ""
		(layer "F.Cu")
		(at 58.357262 -390.07161 90)
		(property "Reference" "R1827"
			(at 0 0 90)
			(layer "F.SilkS")
			(hide yes)
			(effects
				(font
					(size 1.27 1.27)
				)
			)
		)
		(property "Value" ""
			(at 0 0 90)
			(layer "F.Fab")
			(effects
				(font
					(size 1.27 1.27)
				)
			)
		)
		(duplicate_pad_numbers_are_jumpers no)
		(fp_line
			(start 0.7874 -0.4064)
			(end 0.7874 0.4064)
			(stroke
				(width 0.1524)
				(type default)
			)
			(layer "F.SilkS")
		)
		(fp_line
			(start -0.7874 -0.4064)
			(end 0.7874 -0.4064)
			(stroke
				(width 0.1524)
				(type default)
			)
			(layer "F.SilkS")
		)
		(fp_line
			(start 0.7874 0.4064)
			(end -0.7874 0.4064)
			(stroke
				(width 0.1524)
				(type default)
			)
			(layer "F.SilkS")
		)
		(fp_line
			(start -0.7874 0.4064)
			(end -0.7874 -0.4064)
			(stroke
				(width 0.1524)
				(type default)
			)
			(layer "F.SilkS")
		)
		(fp_line
			(start -0.12065 -0.305054)
			(end -0.12065 -0.2794)
			(stroke
				(width 0.1)
				(type default)
			)
			(layer "F.Fab")
		)
		(fp_line
			(start -0.67945 -0.305054)
			(end -0.12065 -0.305054)
			(stroke
				(width 0.1)
				(type default)
			)
			(layer "F.Fab")
		)
		(fp_line
			(start 0.67945 -0.3048)
			(end 0.67945 0.3048)
			(stroke
				(width 0.1)
				(type default)
			)
			(layer "F.Fab")
		)
		(fp_line
			(start 0.12065 -0.3048)
			(end 0.67945 -0.3048)
			(stroke
				(width 0.1)
				(type default)
			)
			(layer "F.Fab")
		)
		(fp_line
			(start 0.12065 -0.2794)
			(end 0.12065 -0.3048)
			(stroke
				(width 0.1)
				(type default)
			)
			(layer "F.Fab")
		)
		(fp_line
			(start -0.12065 -0.2794)
			(end 0.12065 -0.2794)
			(stroke
				(width 0.1)
				(type default)
			)
			(layer "F.Fab")
		)
		(fp_line
			(start 0.120396 0.2794)
			(end -0.12065 0.2794)
			(stroke
				(width 0.1)
				(type default)
			)
			(layer "F.Fab")
		)
		(fp_line
			(start -0.12065 0.2794)
			(end -0.12065 0.3048)
			(stroke
				(width 0.1)
				(type default)
			)
			(layer "F.Fab")
		)
		(fp_line
			(start 0.67945 0.3048)
			(end 0.120396 0.3048)
			(stroke
				(width 0.1)
				(type default)
			)
			(layer "F.Fab")
		)
		(fp_line
			(start 0.120396 0.3048)
			(end 0.120396 0.2794)
			(stroke
				(width 0.1)
				(type default)
			)
			(layer "F.Fab")
		)
		(fp_line
			(start -0.12065 0.3048)
			(end -0.67945 0.3048)
			(stroke
				(width 0.1)
				(type default)
			)
			(layer "F.Fab")
		)
		(fp_line
			(start -0.67945 0.3048)
			(end -0.67945 -0.305054)
			(stroke
				(width 0.1)
				(type default)
			)
			(layer "F.Fab")
		)
		(pad "1" smd circle
			(at -0.40005 0 90)
			(size 0 0)
			(layers "F.Cu" "F.Mask" "F.Paste")
			(net "GPU_THERM_OVERT_R_N")
		)
		(pad "2" smd circle
			(at 0.40005 0 90)
			(size 0 0)
			(layers "F.Cu" "F.Mask" "F.Paste")
			(net "GPU_THERM_OVERT_N")
		)
	)
	(footprint ""
		(layer "F.Cu")
		(at 148.570442 -250.070874 -90)
		(property "Reference" "R1277"
			(at 0 0 270)
			(layer "F.SilkS")
			(hide yes)
			(effects
				(font
					(size 1.27 1.27)
				)
			)
		)
		(property "Value" ""
			(at 0 0 270)
			(layer "F.Fab")
			(effects
				(font
					(size 1.27 1.27)
				)
			)
		)
		(duplicate_pad_numbers_are_jumpers no)
		(fp_line
			(start -0.7874 0.4064)
			(end -0.7874 -0.4064)
			(stroke
				(width 0.1524)
				(type default)
			)
			(layer "F.SilkS")
		)
		(fp_line
			(start 0.7874 0.4064)
			(end -0.7874 0.4064)
			(stroke
				(width 0.1524)
				(type default)
			)
			(layer "F.SilkS")
		)
		(fp_line
			(start -0.7874 -0.4064)
			(end 0.7874 -0.4064)
			(stroke
				(width 0.1524)
				(type default)
			)
			(layer "F.SilkS")
		)
		(fp_line
			(start 0.7874 -0.4064)
			(end 0.7874 0.4064)
			(stroke
				(width 0.1524)
				(type default)
			)
			(layer "F.SilkS")
		)
		(fp_line
			(start -0.67945 0.3048)
			(end -0.67945 -0.305054)
			(stroke
				(width 0.1)
				(type default)
			)
			(layer "F.Fab")
		)
		(fp_line
			(start -0.12065 0.3048)
			(end -0.67945 0.3048)
			(stroke
				(width 0.1)
				(type default)
			)
			(layer "F.Fab")
		)
		(fp_line
			(start 0.120396 0.3048)
			(end 0.120396 0.2794)
			(stroke
				(width 0.1)
				(type default)
			)
			(layer "F.Fab")
		)
		(fp_line
			(start 0.67945 0.3048)
			(end 0.120396 0.3048)
			(stroke
				(width 0.1)
				(type default)
			)
			(layer "F.Fab")
		)
		(fp_line
			(start -0.12065 0.2794)
			(end -0.12065 0.3048)
			(stroke
				(width 0.1)
				(type default)
			)
			(layer "F.Fab")
		)
		(fp_line
			(start 0.120396 0.2794)
			(end -0.12065 0.2794)
			(stroke
				(width 0.1)
				(type default)
			)
			(layer "F.Fab")
		)
		(fp_line
			(start -0.12065 -0.2794)
			(end 0.12065 -0.2794)
			(stroke
				(width 0.1)
				(type default)
			)
			(layer "F.Fab")
		)
		(fp_line
			(start 0.12065 -0.2794)
			(end 0.12065 -0.3048)
			(stroke
				(width 0.1)
				(type default)
			)
			(layer "F.Fab")
		)
		(fp_line
			(start 0.12065 -0.3048)
			(end 0.67945 -0.3048)
			(stroke
				(width 0.1)
				(type default)
			)
			(layer "F.Fab")
		)
		(fp_line
			(start 0.67945 -0.3048)
			(end 0.67945 0.3048)
			(stroke
				(width 0.1)
				(type default)
			)
			(layer "F.Fab")
		)
		(fp_line
			(start -0.67945 -0.305054)
			(end -0.12065 -0.305054)
			(stroke
				(width 0.1)
				(type default)
			)
			(layer "F.Fab")
		)
		(fp_line
			(start -0.12065 -0.305054)
			(end -0.12065 -0.2794)
			(stroke
				(width 0.1)
				(type default)
			)
			(layer "F.Fab")
		)
		(pad "1" smd circle
			(at -0.40005 0 270)
			(size 0 0)
			(layers "F.Cu" "F.Mask" "F.Paste")
			(net "PEX1_MODE_SEL8")
		)
		(pad "2" smd circle
			(at 0.40005 0 270)
			(size 0 0)
			(layers "F.Cu" "F.Mask" "F.Paste")
			(net "P1V8_PEX")
		)
	)
	(footprint ""
		(layer "F.Cu")
		(at 376.34926 -280.994612 -90)
		(property "Reference" "C3586"
			(at 0 0 270)
			(layer "F.SilkS")
			(hide yes)
			(effects
				(font
					(size 1.27 1.27)
				)
			)
		)
		(property "Value" ""
			(at 0 0 270)
			(layer "F.Fab")
			(effects
				(font
					(size 1.27 1.27)
				)
			)
		)
		(duplicate_pad_numbers_are_jumpers no)
		(fp_line
			(start -0.299974 0.150114)
			(end -0.299974 -0.150114)
			(stroke
				(width 0.1)
				(type default)
			)
			(layer "F.Fab")
		)
		(fp_line
			(start 0.299974 0.150114)
			(end -0.299974 0.150114)
			(stroke
				(width 0.1)
				(type default)
			)
			(layer "F.Fab")
		)
		(fp_line
			(start -0.299974 -0.150114)
			(end 0.299974 -0.150114)
			(stroke
				(width 0.1)
				(type default)
			)
			(layer "F.Fab")
		)
		(fp_line
			(start 0.299974 -0.150114)
			(end 0.299974 0.150114)
			(stroke
				(width 0.1)
				(type default)
			)
			(layer "F.Fab")
		)
		(pad "1" smd rect
			(at -0.2667 0 270)
			(size 0.3048 0.381)
			(layers "F.Cu" "F.Mask" "F.Paste")
			(net "P1V8_PLL0_PEX3")
		)
		(pad "2" smd rect
			(at 0.2667 0 270)
			(size 0.3048 0.381)
			(layers "F.Cu" "F.Mask" "F.Paste")
			(net "GND")
		)
	)
	(footprint ""
		(layer "F.Cu")
		(at 104.839008 -231.191562 90)
		(property "Reference" "PL26"
			(at -3.556762 -4.152138 90)
			(unlocked yes)
			(layer "F.SilkS")
			(effects
				(font
					(size 0.7874 0.5842)
					(thickness 0.1524)
				)
				(justify left)
			)
		)
		(property "Value" ""
			(at 0 0 90)
			(layer "F.Fab")
			(effects
				(font
					(size 1.27 1.27)
				)
			)
		)
		(duplicate_pad_numbers_are_jumpers no)
		(fp_line
			(start 3.64998 -3.350006)
			(end 3.64998 -1.8034)
			(stroke
				(width 0.1524)
				(type default)
			)
			(layer "F.SilkS")
		)
		(fp_line
			(start -3.6576 -3.350006)
			(end 3.64998 -3.350006)
			(stroke
				(width 0.1524)
				(type default)
			)
			(layer "F.SilkS")
		)
		(fp_line
			(start -3.64998 -1.8034)
			(end -3.64998 -3.350006)
			(stroke
				(width 0.1524)
				(type default)
			)
			(layer "F.SilkS")
		)
		(fp_line
			(start 3.64998 1.8034)
			(end 3.64998 3.350006)
			(stroke
				(width 0.1524)
				(type default)
			)
			(layer "F.SilkS")
		)
		(fp_line
			(start 3.64998 3.350006)
			(end -3.64998 3.350006)
			(stroke
				(width 0.1524)
				(type default)
			)
			(layer "F.SilkS")
		)
		(fp_line
			(start -3.64998 3.350006)
			(end -3.64998 1.8288)
			(stroke
				(width 0.1524)
				(type default)
			)
			(layer "F.SilkS")
		)
		(fp_line
			(start 3.64998 -3.350006)
			(end 3.64998 3.350006)
			(stroke
				(width 0.1)
				(type default)
			)
			(layer "F.Fab")
		)
		(fp_line
			(start -3.64998 -3.350006)
			(end 3.64998 -3.350006)
			(stroke
				(width 0.1)
				(type default)
			)
			(layer "F.Fab")
		)
		(fp_line
			(start 3.64998 3.350006)
			(end -3.64998 3.350006)
			(stroke
				(width 0.1)
				(type default)
			)
			(layer "F.Fab")
		)
		(fp_line
			(start -3.64998 3.350006)
			(end -3.64998 -3.350006)
			(stroke
				(width 0.1)
				(type default)
			)
			(layer "F.Fab")
		)
		(pad "1" smd rect
			(at -2.92481 0 90)
			(size 2.15392 3.302)
			(layers "F.Cu" "F.Mask" "F.Paste")
			(net "SW_P1V8_PEX_PH")
		)
		(pad "2" smd rect
			(at 2.92481 0 90)
			(size 2.15392 3.302)
			(layers "F.Cu" "F.Mask" "F.Paste")
			(net "P1V8_PEX_R")
		)
	)
	(footprint ""
		(layer "F.Cu")
		(at 137.622788 -350.098614 90)
		(property "Reference" "C2266"
			(at 0 0 90)
			(layer "F.SilkS")
			(hide yes)
			(effects
				(font
					(size 1.27 1.27)
				)
			)
		)
		(property "Value" ""
			(at 0 0 90)
			(layer "F.Fab")
			(effects
				(font
					(size 1.27 1.27)
				)
			)
		)
		(duplicate_pad_numbers_are_jumpers no)
		(fp_line
			(start 0.299974 -0.150114)
			(end 0.299974 0.150114)
			(stroke
				(width 0.1)
				(type default)
			)
			(layer "F.Fab")
		)
		(fp_line
			(start -0.299974 -0.150114)
			(end 0.299974 -0.150114)
			(stroke
				(width 0.1)
				(type default)
			)
			(layer "F.Fab")
		)
		(fp_line
			(start 0.299974 0.150114)
			(end -0.299974 0.150114)
			(stroke
				(width 0.1)
				(type default)
			)
			(layer "F.Fab")
		)
		(fp_line
			(start -0.299974 0.150114)
			(end -0.299974 -0.150114)
			(stroke
				(width 0.1)
				(type default)
			)
			(layer "F.Fab")
		)
		(pad "1" smd rect
			(at -0.2667 0 90)
			(size 0.3048 0.381)
			(layers "F.Cu" "F.Mask" "F.Paste")
			(net "P5E_PEX1_STN5_TX_DN<84>")
		)
		(pad "2" smd rect
			(at 0.2667 0 90)
			(size 0.3048 0.381)
			(layers "F.Cu" "F.Mask" "F.Paste")
			(net "P5E_PEX1_STN5_TX_C_DN<84>")
		)
	)
	(footprint ""
		(layer "F.Cu")
		(at 319.140332 -143.182848 90)
		(property "Reference" "C4003"
			(at 0 0 90)
			(layer "F.SilkS")
			(hide yes)
			(effects
				(font
					(size 1.27 1.27)
				)
			)
		)
		(property "Value" ""
			(at 0 0 90)
			(layer "F.Fab")
			(effects
				(font
					(size 1.27 1.27)
				)
			)
		)
		(duplicate_pad_numbers_are_jumpers no)
		(fp_line
			(start 0.7874 -0.4064)
			(end 0.7874 0.4064)
			(stroke
				(width 0.1524)
				(type default)
			)
			(layer "F.SilkS")
		)
		(fp_line
			(start -0.7874 -0.4064)
			(end 0.7874 -0.4064)
			(stroke
				(width 0.1524)
				(type default)
			)
			(layer "F.SilkS")
		)
		(fp_line
			(start 0.7874 0.4064)
			(end -0.7874 0.4064)
			(stroke
				(width 0.1524)
				(type default)
			)
			(layer "F.SilkS")
		)
		(fp_line
			(start -0.7874 0.4064)
			(end -0.7874 -0.4064)
			(stroke
				(width 0.1524)
				(type default)
			)
			(layer "F.SilkS")
		)
		(fp_line
			(start -0.12065 -0.305054)
			(end -0.12065 -0.2794)
			(stroke
				(width 0.1)
				(type default)
			)
			(layer "F.Fab")
		)
		(fp_line
			(start -0.67945 -0.305054)
			(end -0.12065 -0.305054)
			(stroke
				(width 0.1)
				(type default)
			)
			(layer "F.Fab")
		)
		(fp_line
			(start 0.67945 -0.3048)
			(end 0.67945 0.3048)
			(stroke
				(width 0.1)
				(type default)
			)
			(layer "F.Fab")
		)
		(fp_line
			(start 0.12065 -0.3048)
			(end 0.67945 -0.3048)
			(stroke
				(width 0.1)
				(type default)
			)
			(layer "F.Fab")
		)
		(fp_line
			(start 0.12065 -0.2794)
			(end 0.12065 -0.3048)
			(stroke
				(width 0.1)
				(type default)
			)
			(layer "F.Fab")
		)
		(fp_line
			(start -0.12065 -0.2794)
			(end 0.12065 -0.2794)
			(stroke
				(width 0.1)
				(type default)
			)
			(layer "F.Fab")
		)
		(fp_line
			(start 0.120396 0.2794)
			(end -0.12065 0.2794)
			(stroke
				(width 0.1)
				(type default)
			)
			(layer "F.Fab")
		)
		(fp_line
			(start -0.12065 0.2794)
			(end -0.12065 0.3048)
			(stroke
				(width 0.1)
				(type default)
			)
			(layer "F.Fab")
		)
		(fp_line
			(start 0.67945 0.3048)
			(end 0.120396 0.3048)
			(stroke
				(width 0.1)
				(type default)
			)
			(layer "F.Fab")
		)
		(fp_line
			(start 0.120396 0.3048)
			(end 0.120396 0.2794)
			(stroke
				(width 0.1)
				(type default)
			)
			(layer "F.Fab")
		)
		(fp_line
			(start -0.12065 0.3048)
			(end -0.67945 0.3048)
			(stroke
				(width 0.1)
				(type default)
			)
			(layer "F.Fab")
		)
		(fp_line
			(start -0.67945 0.3048)
			(end -0.67945 -0.305054)
			(stroke
				(width 0.1)
				(type default)
			)
			(layer "F.Fab")
		)
		(pad "1" smd circle
			(at -0.40005 0 90)
			(size 0 0)
			(layers "F.Cu" "F.Mask" "F.Paste")
			(net "PRSNT_NIC5_R_N")
		)
		(pad "2" smd circle
			(at 0.40005 0 90)
			(size 0 0)
			(layers "F.Cu" "F.Mask" "F.Paste")
			(net "GND")
		)
	)
	(footprint ""
		(layer "F.Cu")
		(at 202.774296 -303.938686 -90)
		(property "Reference" "R6808"
			(at 0 0 270)
			(layer "F.SilkS")
			(hide yes)
			(effects
				(font
					(size 1.27 1.27)
				)
			)
		)
		(property "Value" ""
			(at 0 0 270)
			(layer "F.Fab")
			(effects
				(font
					(size 1.27 1.27)
				)
			)
		)
		(duplicate_pad_numbers_are_jumpers no)
		(fp_line
			(start -0.7874 0.4064)
			(end -0.7874 -0.4064)
			(stroke
				(width 0.1524)
				(type default)
			)
			(layer "F.SilkS")
		)
		(fp_line
			(start 0.7874 0.4064)
			(end -0.7874 0.4064)
			(stroke
				(width 0.1524)
				(type default)
			)
			(layer "F.SilkS")
		)
		(fp_line
			(start -0.7874 -0.4064)
			(end 0.7874 -0.4064)
			(stroke
				(width 0.1524)
				(type default)
			)
			(layer "F.SilkS")
		)
		(fp_line
			(start 0.7874 -0.4064)
			(end 0.7874 0.4064)
			(stroke
				(width 0.1524)
				(type default)
			)
			(layer "F.SilkS")
		)
		(fp_line
			(start -0.67945 0.3048)
			(end -0.67945 -0.305054)
			(stroke
				(width 0.1)
				(type default)
			)
			(layer "F.Fab")
		)
		(fp_line
			(start -0.12065 0.3048)
			(end -0.67945 0.3048)
			(stroke
				(width 0.1)
				(type default)
			)
			(layer "F.Fab")
		)
		(fp_line
			(start 0.120396 0.3048)
			(end 0.120396 0.2794)
			(stroke
				(width 0.1)
				(type default)
			)
			(layer "F.Fab")
		)
		(fp_line
			(start 0.67945 0.3048)
			(end 0.120396 0.3048)
			(stroke
				(width 0.1)
				(type default)
			)
			(layer "F.Fab")
		)
		(fp_line
			(start -0.12065 0.2794)
			(end -0.12065 0.3048)
			(stroke
				(width 0.1)
				(type default)
			)
			(layer "F.Fab")
		)
		(fp_line
			(start 0.120396 0.2794)
			(end -0.12065 0.2794)
			(stroke
				(width 0.1)
				(type default)
			)
			(layer "F.Fab")
		)
		(fp_line
			(start -0.12065 -0.2794)
			(end 0.12065 -0.2794)
			(stroke
				(width 0.1)
				(type default)
			)
			(layer "F.Fab")
		)
		(fp_line
			(start 0.12065 -0.2794)
			(end 0.12065 -0.3048)
			(stroke
				(width 0.1)
				(type default)
			)
			(layer "F.Fab")
		)
		(fp_line
			(start 0.12065 -0.3048)
			(end 0.67945 -0.3048)
			(stroke
				(width 0.1)
				(type default)
			)
			(layer "F.Fab")
		)
		(fp_line
			(start 0.67945 -0.3048)
			(end 0.67945 0.3048)
			(stroke
				(width 0.1)
				(type default)
			)
			(layer "F.Fab")
		)
		(fp_line
			(start -0.67945 -0.305054)
			(end -0.12065 -0.305054)
			(stroke
				(width 0.1)
				(type default)
			)
			(layer "F.Fab")
		)
		(fp_line
			(start -0.12065 -0.305054)
			(end -0.12065 -0.2794)
			(stroke
				(width 0.1)
				(type default)
			)
			(layer "F.Fab")
		)
		(pad "1" smd circle
			(at -0.40005 0 270)
			(size 0 0)
			(layers "F.Cu" "F.Mask" "F.Paste")
			(net "SMB_PEX1_R_SCL")
		)
		(pad "2" smd circle
			(at 0.40005 0 270)
			(size 0 0)
			(layers "F.Cu" "F.Mask" "F.Paste")
			(net "SMB_PEX1_SCL")
		)
	)
)
